(kicad_pcb
	(version 20240108)
	(generator "pcbnew")
	(generator_version "8.0")
	(general
		(thickness 1.62)
		(legacy_teardrops no)
	)
	(paper "A4")
	(title_block
		(title "Jetson Orin Baseboard")
		(date "2025-03-12")
		(rev "1.3.4")
		(company "Antmicro Ltd")
		(comment 1 "www.antmicro.com")
		(comment 9 "footprint 59 of 677 (J15), pads 171-254 of 264")
	)
	(layers
		(0 "F.Cu" signal)
		(1 "In1.Cu" signal)
		(2 "In2.Cu" signal)
		(3 "In3.Cu" signal)
		(4 "In4.Cu" jumper)
		(5 "In5.Cu" signal)
		(6 "In6.Cu" signal)
		(31 "B.Cu" signal)
		(32 "B.Adhes" user "B.Adhesive")
		(33 "F.Adhes" user "F.Adhesive")
		(34 "B.Paste" user)
		(35 "F.Paste" user)
		(36 "B.SilkS" user "B.Silkscreen")
		(37 "F.SilkS" user "F.Silkscreen")
		(38 "B.Mask" user)
		(39 "F.Mask" user)
		(40 "Dwgs.User" user "User.Drawings")
		(41 "Cmts.User" user "User.Comments")
		(42 "Eco1.User" user "User.Eco1")
		(43 "Eco2.User" user "User.Eco2")
		(44 "Edge.Cuts" user)
		(45 "Margin" user)
		(46 "B.CrtYd" user "B.Courtyard")
		(47 "F.CrtYd" user "F.Courtyard")
		(48 "B.Fab" user)
		(49 "F.Fab" user)
	)
	(footprint "antmicro-footprints:TE_2309413"
		(locked yes)
		(layer "F.Cu")
		(at 92.706 84.0225)
		(descr "260 pin DDR4 SODIMM Right Angle Socket, 9.2 mm (0.362 in) Stack Height, https://www.te.com/global-en/product-2309413-1.html")
		(tags "ddr4 sodimm right angle 9.2mm height jetson som")
		(property "Reference" "J15"
			(at -36.75 -13.25 0)
			(layer "F.SilkS")
			(effects
				(font
					(size 0.7 0.7)
					(thickness 0.15)
				)
				(justify left bottom)
			)
		)
		(property "Value" "Bus_DDR4_SODIMM_CUSTOM_Jetson-Orin-H9.2mm-socket"
			(at -38 14.25 0)
			(layer "F.Fab")
			(effects
				(font
					(size 0.7 0.7)
					(thickness 0.15)
				)
				(justify left bottom)
			)
		)
		(property "Footprint" "antmicro-footprints:TE_2309413"
			(at 0 0 0)
			(layer "F.Fab")
			(hide yes)
			(effects
				(font
					(size 1.27 1.27)
					(thickness 0.15)
				)
			)
		)
		(property "Datasheet" "https://developer.nvidia.com/jetson-orin-nx-series-data-sheet"
			(at 0 0 0)
			(layer "F.Fab")
			(hide yes)
			(effects
				(font
					(size 1.27 1.27)
					(thickness 0.15)
				)
			)
		)
		(property "Author" "Antmicro"
			(at 0 0 0)
			(layer "F.Fab")
			(hide yes)
			(effects
				(font
					(size 1 1)
					(thickness 0.15)
				)
			)
		)
		(property "License" "Apache-2.0"
			(at 0 0 0)
			(layer "F.Fab")
			(hide yes)
			(effects
				(font
					(size 1 1)
					(thickness 0.15)
				)
			)
		)
		(property "MPN" "2309413-1"
			(at 0 0 0)
			(layer "F.Fab")
			(hide yes)
			(effects
				(font
					(size 1 1)
					(thickness 0.15)
				)
			)
		)
		(property "Manufacturer" "TE Connectivity"
			(at 0 0 0)
			(layer "F.Fab")
			(hide yes)
			(effects
				(font
					(size 1 1)
					(thickness 0.15)
				)
			)
		)
		(sheetname "SoM")
		(sheetfile "som.kicad_sch")
		(attr smd)
		(pad "169" smd rect
			(at -10.631 -12.026 90)
			(size 1.75 0.3)
			(layers "F.Cu" "F.Paste" "F.Mask")
			(net 61 "PCIE1_RX0_P")
			(pinfunction "PCIE1_RX0_P")
			(pintype "passive")
		)
		(pad "170" smd rect
			(at -10.881 -3.826 90)
			(size 1.75 0.3)
			(layers "F.Cu" "F.Paste" "F.Mask")
			(net 1 "GND")
			(pinfunction "GND")
			(pintype "passive")
		)
		(pad "171" smd rect
			(at -11.131 -12.026 90)
			(size 1.75 0.3)
			(layers "F.Cu" "F.Paste" "F.Mask")
			(net 1 "GND")
			(pinfunction "GND")
			(pintype "passive")
		)
		(pad "172" smd rect
			(at -11.381 -3.826 90)
			(size 1.75 0.3)
			(layers "F.Cu" "F.Paste" "F.Mask")
			(net 450 "PCIE1_TX0_N")
			(pinfunction "PCIE1_TX0_N")
			(pintype "passive")
		)
		(pad "173" smd rect
			(at -11.631 -12.026 90)
			(size 1.75 0.3)
			(layers "F.Cu" "F.Paste" "F.Mask")
			(net 62 "PCIE1_CLK_N")
			(pinfunction "PCIE1_CLK_N")
			(pintype "passive")
		)
		(pad "174" smd rect
			(at -11.881 -3.826 90)
			(size 1.75 0.3)
			(layers "F.Cu" "F.Paste" "F.Mask")
			(net 451 "PCIE1_TX0_P")
			(pinfunction "PCIE1_TX0_P")
			(pintype "passive")
		)
		(pad "175" smd rect
			(at -12.131 -12.026 90)
			(size 1.75 0.3)
			(layers "F.Cu" "F.Paste" "F.Mask")
			(net 63 "PCIE1_CLK_P")
			(pinfunction "PCIE1_CLK_P")
			(pintype "passive")
		)
		(pad "176" smd rect
			(at -12.381 -3.826 90)
			(size 1.75 0.3)
			(layers "F.Cu" "F.Paste" "F.Mask")
			(net 1 "GND")
			(pinfunction "GND")
			(pintype "passive")
		)
		(pad "177" smd rect
			(at -12.631 -12.026 90)
			(size 1.75 0.3)
			(layers "F.Cu" "F.Paste" "F.Mask")
			(net 1 "GND")
			(pinfunction "GND")
			(pintype "passive")
		)
		(pad "178" smd rect
			(at -12.881 -3.826 90)
			(size 1.75 0.3)
			(layers "F.Cu" "F.Paste" "F.Mask")
			(net 452 "/SoM/~{MOD_SLEEP}")
			(pinfunction "~{MOD_SLEEP}")
			(pintype "passive")
		)
		(pad "179" smd rect
			(at -13.131 -12.026 90)
			(size 1.75 0.3)
			(layers "F.Cu" "F.Paste" "F.Mask")
			(net 453 "PCIE_WAKE*")
			(pinfunction "~{PCIE_WAKE}")
			(pintype "passive")
		)
		(pad "180" smd rect
			(at -13.381 -3.826 90)
			(size 1.75 0.3)
			(layers "F.Cu" "F.Paste" "F.Mask")
			(net 454 "PCIE0_CLKREQ*")
			(pinfunction "~{PCIE0_CLKREQ}")
			(pintype "passive")
		)
		(pad "181" smd rect
			(at -13.631 -12.026 90)
			(size 1.75 0.3)
			(layers "F.Cu" "F.Paste" "F.Mask")
			(net 455 "PCIE0_RST*")
			(pinfunction "~{PCIE0_RST}")
			(pintype "passive")
		)
		(pad "182" smd rect
			(at -13.881 -3.826 90)
			(size 1.75 0.3)
			(layers "F.Cu" "F.Paste" "F.Mask")
			(net 64 "PCIE1_CLKREQ*")
			(pinfunction "~{PCIE1_CLKREQ}")
			(pintype "passive")
		)
		(pad "183" smd rect
			(at -14.131 -12.026 90)
			(size 1.75 0.3)
			(layers "F.Cu" "F.Paste" "F.Mask")
			(net 65 "PCIE1_RST*")
			(pinfunction "~{PCIE1_RST}")
			(pintype "passive")
		)
		(pad "184" smd rect
			(at -14.381 -3.826 90)
			(size 1.75 0.3)
			(layers "F.Cu" "F.Paste" "F.Mask")
			(net 66 "GBE_MDI0_N")
			(pinfunction "GBE_MDI0_N")
			(pintype "passive")
		)
		(pad "185" smd rect
			(at -14.631 -12.026 90)
			(size 1.75 0.3)
			(layers "F.Cu" "F.Paste" "F.Mask")
			(net 252 "SYS_SCL")
			(pinfunction "I2C0_SCL")
			(pintype "passive")
		)
		(pad "186" smd rect
			(at -14.881 -3.826 90)
			(size 1.75 0.3)
			(layers "F.Cu" "F.Paste" "F.Mask")
			(net 67 "GBE_MDI0_P")
			(pinfunction "GBE_MDI0_P")
			(pintype "passive")
		)
		(pad "187" smd rect
			(at -15.131 -12.026 90)
			(size 1.75 0.3)
			(layers "F.Cu" "F.Paste" "F.Mask")
			(net 251 "SYS_SDA")
			(pinfunction "I2C0_SDA")
			(pintype "passive")
		)
		(pad "188" smd rect
			(at -15.381 -3.826 90)
			(size 1.75 0.3)
			(layers "F.Cu" "F.Paste" "F.Mask")
			(net 457 "GBE_LED_LINK")
			(pinfunction "GBE_LED_LINK")
			(pintype "passive")
		)
		(pad "189" smd rect
			(at -15.631 -12.026 90)
			(size 1.75 0.3)
			(layers "F.Cu" "F.Paste" "F.Mask")
			(net 659 "I2C1_SCL")
			(pinfunction "I2C1_SCL")
			(pintype "passive")
		)
		(pad "190" smd rect
			(at -15.881 -3.826 90)
			(size 1.75 0.3)
			(layers "F.Cu" "F.Paste" "F.Mask")
			(net 68 "GBE_MDI1_N")
			(pinfunction "GBE_MDI1_N")
			(pintype "passive")
		)
		(pad "191" smd rect
			(at -16.13 -12.026 90)
			(size 1.75 0.3)
			(layers "F.Cu" "F.Paste" "F.Mask")
			(net 660 "I2C1_SDA")
			(pinfunction "I2C1_SDA")
			(pintype "passive")
		)
		(pad "192" smd rect
			(at -16.38 -3.826 90)
			(size 1.75 0.3)
			(layers "F.Cu" "F.Paste" "F.Mask")
			(net 69 "GBE_MDI1_P")
			(pinfunction "GBE_MDI1_P")
			(pintype "passive")
		)
		(pad "193" smd rect
			(at -16.63 -12.026 90)
			(size 1.75 0.3)
			(layers "F.Cu" "F.Paste" "F.Mask")
			(net 70 "I2S0_SDOUT")
			(pinfunction "I2S0_DOUT")
			(pintype "passive")
		)
		(pad "194" smd rect
			(at -16.88 -3.826 90)
			(size 1.75 0.3)
			(layers "F.Cu" "F.Paste" "F.Mask")
			(net 459 "GBE_LED_ACT")
			(pinfunction "GBE_LED_ACT")
			(pintype "passive")
		)
		(pad "195" smd rect
			(at -17.13 -12.026 90)
			(size 1.75 0.3)
			(layers "F.Cu" "F.Paste" "F.Mask")
			(net 71 "I2S0_SDIN")
			(pinfunction "I2S0_DIN")
			(pintype "passive")
		)
		(pad "196" smd rect
			(at -17.38 -3.826 90)
			(size 1.75 0.3)
			(layers "F.Cu" "F.Paste" "F.Mask")
			(net 72 "GBE_MDI2_N")
			(pinfunction "GBE_MDI2_N")
			(pintype "passive")
		)
		(pad "197" smd rect
			(at -17.63 -12.026 90)
			(size 1.75 0.3)
			(layers "F.Cu" "F.Paste" "F.Mask")
			(net 73 "I2S0_LRCK")
			(pinfunction "I2S0_FS")
			(pintype "passive")
		)
		(pad "198" smd rect
			(at -17.88 -3.826 90)
			(size 1.75 0.3)
			(layers "F.Cu" "F.Paste" "F.Mask")
			(net 74 "GBE_MDI2_P")
			(pinfunction "GBE_MDI2_P")
			(pintype "passive")
		)
		(pad "199" smd rect
			(at -18.13 -12.026 90)
			(size 1.75 0.3)
			(layers "F.Cu" "F.Paste" "F.Mask")
			(net 75 "I2S0_SCLK")
			(pinfunction "I2S0_SCLK")
			(pintype "passive")
		)
		(pad "200" smd rect
			(at -18.38 -3.826 90)
			(size 1.75 0.3)
			(layers "F.Cu" "F.Paste" "F.Mask")
			(net 1 "GND")
			(pinfunction "GND")
			(pintype "passive")
		)
		(pad "201" smd rect
			(at -18.63 -12.026 90)
			(size 1.75 0.3)
			(layers "F.Cu" "F.Paste" "F.Mask")
			(net 1 "GND")
			(pinfunction "GND")
			(pintype "passive")
		)
		(pad "202" smd rect
			(at -18.88 -3.826 90)
			(size 1.75 0.3)
			(layers "F.Cu" "F.Paste" "F.Mask")
			(net 76 "GBE_MDI3_N")
			(pinfunction "GBE_MDI3_N")
			(pintype "passive")
		)
		(pad "203" smd rect
			(at -19.13 -12.026 90)
			(size 1.75 0.3)
			(layers "F.Cu" "F.Paste" "F.Mask")
			(net 460 "UART1_TXD")
			(pinfunction "UART1_TXD")
			(pintype "passive")
		)
		(pad "204" smd rect
			(at -19.38 -3.826 90)
			(size 1.75 0.3)
			(layers "F.Cu" "F.Paste" "F.Mask")
			(net 77 "GBE_MDI3_P")
			(pinfunction "GBE_MDI3_P")
			(pintype "passive")
		)
		(pad "205" smd rect
			(at -19.63 -12.026 90)
			(size 1.75 0.3)
			(layers "F.Cu" "F.Paste" "F.Mask")
			(net 461 "UART1_RXD")
			(pinfunction "UART1_RXD")
			(pintype "passive")
		)
		(pad "206" smd rect
			(at -19.88 -3.826 90)
			(size 1.75 0.3)
			(layers "F.Cu" "F.Paste" "F.Mask")
			(net 102 "GPIO07")
			(pinfunction "GPIO07/PWM")
			(pintype "passive")
		)
		(pad "207" smd rect
			(at -20.13 -12.026 90)
			(size 1.75 0.3)
			(layers "F.Cu" "F.Paste" "F.Mask")
			(net 748 "unconnected-(J15C-~{UART1_RTS}-Pad207)")
			(pinfunction "~{UART1_RTS}")
			(pintype "passive+no_connect")
		)
		(pad "208" smd rect
			(at -20.38 -3.826 90)
			(size 1.75 0.3)
			(layers "F.Cu" "F.Paste" "F.Mask")
			(net 463 "FAN_TACH")
			(pinfunction "Fan_Tach/GPIO08")
			(pintype "passive")
		)
		(pad "209" smd rect
			(at -20.63 -12.026 90)
			(size 1.75 0.3)
			(layers "F.Cu" "F.Paste" "F.Mask")
			(net 749 "unconnected-(J15C-~{UART1_CTS}-Pad209)")
			(pinfunction "~{UART1_CTS}")
			(pintype "passive+no_connect")
		)
		(pad "210" smd rect
			(at -20.88 -3.826 90)
			(size 1.75 0.3)
			(layers "F.Cu" "F.Paste" "F.Mask")
			(net 750 "Net-(J15A-CLK_32K_OUT)")
			(pinfunction "CLK_32K_OUT")
			(pintype "passive")
		)
		(pad "211" smd rect
			(at -21.13 -12.026 90)
			(size 1.75 0.3)
			(layers "F.Cu" "F.Paste" "F.Mask")
			(net 78 "GPIO09")
			(pinfunction "GPIO09/AUD_MCLK")
			(pintype "passive")
		)
		(pad "212" smd rect
			(at -21.38 -3.826 90)
			(size 1.75 0.3)
			(layers "F.Cu" "F.Paste" "F.Mask")
			(net 714 "GPIO010")
			(pinfunction "GPIO10")
			(pintype "passive")
		)
		(pad "213" smd rect
			(at -21.63 -12.026 90)
			(size 1.75 0.3)
			(layers "F.Cu" "F.Paste" "F.Mask")
			(net 81 "SCL_CAM")
			(pinfunction "CAM_I2C_SCL")
			(pintype "passive")
		)
		(pad "214" smd rect
			(at -21.88 -3.826 90)
			(size 1.75 0.3)
			(layers "F.Cu" "F.Paste" "F.Mask")
			(net 80 "/SoM/~{FORCE_RECOVERY}")
			(pinfunction "~{FORCE_RECOVERY}")
			(pintype "passive")
		)
		(pad "215" smd rect
			(at -22.13 -12.026 90)
			(size 1.75 0.3)
			(layers "F.Cu" "F.Paste" "F.Mask")
			(net 79 "SDA_CAM")
			(pinfunction "CAM_I2C_SDA")
			(pintype "passive")
		)
		(pad "216" smd rect
			(at -22.38 -3.826 90)
			(size 1.75 0.3)
			(layers "F.Cu" "F.Paste" "F.Mask")
			(net 82 "GPIO11")
			(pinfunction "GPIO11/CLK")
			(pintype "passive")
		)
		(pad "217" smd rect
			(at -22.63 -12.026 90)
			(size 1.75 0.3)
			(layers "F.Cu" "F.Paste" "F.Mask")
			(net 789 "MODULE_ID")
			(pinfunction "GND(MODULE_ID)")
			(pintype "passive")
		)
		(pad "218" smd rect
			(at -22.88 -3.826 90)
			(size 1.75 0.3)
			(layers "F.Cu" "F.Paste" "F.Mask")
			(net 752 "Net-(J15H-GPIO12{slash}PWM)")
			(pinfunction "GPIO12/PWM")
			(pintype "passive")
		)
		(pad "219" smd rect
			(at -23.13 -12.026 90)
			(size 1.75 0.3)
			(layers "F.Cu" "F.Paste" "F.Mask")
			(net 103 "PCIE2_RST*")
			(pinfunction "~{PCIE2_RST}")
			(pintype "passive")
		)
		(pad "220" smd rect
			(at -23.38 -3.826 90)
			(size 1.75 0.3)
			(layers "F.Cu" "F.Paste" "F.Mask")
			(net 467 "I2S1_SDOUT")
			(pinfunction "I2S1_DOUT")
			(pintype "passive")
		)
		(pad "221" smd rect
			(at -23.63 -12.026 90)
			(size 1.75 0.3)
			(layers "F.Cu" "F.Paste" "F.Mask")
			(net 104 "PCIE2_CLKREQ*")
			(pinfunction "~{PCIE2_CLKREQ}")
			(pintype "passive")
		)
		(pad "222" smd rect
			(at -23.88 -3.826 90)
			(size 1.75 0.3)
			(layers "F.Cu" "F.Paste" "F.Mask")
			(net 468 "I2S1_SDIN")
			(pinfunction "I2S1_DIN")
			(pintype "passive")
		)
		(pad "223" smd rect
			(at -24.13 -12.026 90)
			(size 1.75 0.3)
			(layers "F.Cu" "F.Paste" "F.Mask")
			(net 120 "PCIE3_RST*")
			(pinfunction "~{PCIE3_RST}")
			(pintype "passive")
		)
		(pad "224" smd rect
			(at -24.38 -3.826 90)
			(size 1.75 0.3)
			(layers "F.Cu" "F.Paste" "F.Mask")
			(net 469 "I2S1_LRCK")
			(pinfunction "I2S1_FS")
			(pintype "passive")
		)
		(pad "225" smd rect
			(at -24.63 -12.026 90)
			(size 1.75 0.3)
			(layers "F.Cu" "F.Paste" "F.Mask")
			(net 128 "PCIE3_CLKREQ*")
			(pinfunction "~{PCIE3_CLKREQ}")
			(pintype "passive")
		)
		(pad "226" smd rect
			(at -24.88 -3.826 90)
			(size 1.75 0.3)
			(layers "F.Cu" "F.Paste" "F.Mask")
			(net 470 "I2S1_SCLK")
			(pinfunction "I2S1_SCLK")
			(pintype "passive")
		)
		(pad "227" smd rect
			(at -25.13 -12.026 90)
			(size 1.75 0.3)
			(layers "F.Cu" "F.Paste" "F.Mask")
			(net 471 "PCIE3_CLK_N")
			(pinfunction "PCIE3_CLK_N")
			(pintype "passive")
		)
		(pad "228" smd rect
			(at -25.38 -3.826 90)
			(size 1.75 0.3)
			(layers "F.Cu" "F.Paste" "F.Mask")
			(net 753 "Net-(J15H-GPIO13{slash}PWM)")
			(pinfunction "GPIO13/PWM")
			(pintype "passive")
		)
		(pad "229" smd rect
			(at -25.63 -12.026 90)
			(size 1.75 0.3)
			(layers "F.Cu" "F.Paste" "F.Mask")
			(net 472 "PCIE3_CLK_P")
			(pinfunction "PCIE3_CLK_P")
			(pintype "passive")
		)
		(pad "230" smd rect
			(at -25.88 -3.826 90)
			(size 1.75 0.3)
			(layers "F.Cu" "F.Paste" "F.Mask")
			(net 473 "FAN_PWM")
			(pinfunction "GPIO14/PWM")
			(pintype "passive")
		)
		(pad "231" smd rect
			(at -26.13 -12.026 90)
			(size 1.75 0.3)
			(layers "F.Cu" "F.Paste" "F.Mask")
			(net 1 "GND")
			(pinfunction "GND")
			(pintype "passive")
		)
		(pad "232" smd rect
			(at -26.38 -3.826 90)
			(size 1.75 0.3)
			(layers "F.Cu" "F.Paste" "F.Mask")
			(net 129 "I2C2_SCL")
			(pinfunction "I2C2_SCL")
			(pintype "passive")
		)
		(pad "233" smd rect
			(at -26.63 -12.026 90)
			(size 1.75 0.3)
			(layers "F.Cu" "F.Paste" "F.Mask")
			(net 474 "~{SHUTDOWN_REQ}")
			(pinfunction "~{SHUTDOWN_REQ}")
			(pintype "passive")
		)
		(pad "234" smd rect
			(at -26.88 -3.826 90)
			(size 1.75 0.3)
			(layers "F.Cu" "F.Paste" "F.Mask")
			(net 130 "I2C2_SDA")
			(pinfunction "I2C2_SDA")
			(pintype "passive")
		)
		(pad "235" smd rect
			(at -27.13 -12.026 90)
			(size 1.75 0.3)
			(layers "F.Cu" "F.Paste" "F.Mask")
			(net 85 "/SoM/PMIC_BBAT")
			(pinfunction "PMIC_BBAT")
			(pintype "passive")
		)
		(pad "236" smd rect
			(at -27.38 -3.826 90)
			(size 1.75 0.3)
			(layers "F.Cu" "F.Paste" "F.Mask")
			(net 168 "/SoM/DEBUG_TXD_1V8")
			(pinfunction "UART2_TXD")
			(pintype "passive")
		)
		(pad "237" smd rect
			(at -27.63 -12.026 90)
			(size 1.75 0.3)
			(layers "F.Cu" "F.Paste" "F.Mask")
			(net 476 "POWER_EN")
			(pinfunction "POWER_EN")
			(pintype "passive")
		)
		(pad "238" smd rect
			(at -27.88 -3.826 90)
			(size 1.75 0.3)
			(layers "F.Cu" "F.Paste" "F.Mask")
			(net 327 "/SoM/DEBUG_RXD_1V8")
			(pinfunction "UART2_RXD")
			(pintype "passive")
		)
		(pad "239" smd rect
			(at -28.13 -12.026 90)
			(size 1.75 0.3)
			(layers "F.Cu" "F.Paste" "F.Mask")
			(net 86 "~{RESET}")
			(pinfunction "~{SYS_RESET}")
			(pintype "passive")
		)
		(pad "240" smd rect
			(at -28.38 -3.826 90)
			(size 1.75 0.3)
			(layers "F.Cu" "F.Paste" "F.Mask")
			(net 478 "/SoM/SLEEP{slash}~{WAKE}")
			(pinfunction "SLEEP/~{WAKE}")
			(pintype "passive")
		)
		(pad "241" smd rect
			(at -28.63 -12.026 90)
			(size 1.75 0.3)
			(layers "F.Cu" "F.Paste" "F.Mask")
			(net 1 "GND")
			(pinfunction "GND")
			(pintype "passive")
		)
		(pad "242" smd rect
			(at -28.88 -3.826 90)
			(size 1.75 0.3)
			(layers "F.Cu" "F.Paste" "F.Mask")
			(net 1 "GND")
			(pinfunction "GND")
			(pintype "passive")
		)
		(pad "243" smd rect
			(at -29.13 -12.026 90)
			(size 1.75 0.3)
			(layers "F.Cu" "F.Paste" "F.Mask")
			(net 1 "GND")
			(pinfunction "GND")
			(pintype "passive")
		)
		(pad "244" smd rect
			(at -29.38 -3.826 90)
			(size 1.75 0.3)
			(layers "F.Cu" "F.Paste" "F.Mask")
			(net 1 "GND")
			(pinfunction "GND")
			(pintype "passive")
		)
		(pad "245" smd rect
			(at -29.63 -12.026 90)
			(size 1.75 0.3)
			(layers "F.Cu" "F.Paste" "F.Mask")
			(net 1 "GND")
			(pinfunction "GND")
			(pintype "passive")
		)
		(pad "246" smd rect
			(at -29.88 -3.826 90)
			(size 1.75 0.3)
			(layers "F.Cu" "F.Paste" "F.Mask")
			(net 1 "GND")
			(pinfunction "GND")
			(pintype "passive")
		)
		(pad "247" smd rect
			(at -30.13 -12.026 90)
			(size 1.75 0.3)
			(layers "F.Cu" "F.Paste" "F.Mask")
			(net 1 "GND")
			(pinfunction "GND")
			(pintype "passive")
		)
		(pad "248" smd rect
			(at -30.38 -3.826 90)
			(size 1.75 0.3)
			(layers "F.Cu" "F.Paste" "F.Mask")
			(net 1 "GND")
			(pinfunction "GND")
			(pintype "passive")
		)
		(pad "249" smd rect
			(at -30.63 -12.026 90)
			(size 1.75 0.3)
			(layers "F.Cu" "F.Paste" "F.Mask")
			(net 1 "GND")
			(pinfunction "GND")
			(pintype "passive")
		)
		(pad "250" smd rect
			(at -30.88 -3.826 90)
			(size 1.75 0.3)
			(layers "F.Cu" "F.Paste" "F.Mask")
			(net 1 "GND")
			(pinfunction "GND")
			(pintype "passive")
		)
		(pad "251" smd rect
			(at -31.13 -12.026 90)
			(size 1.75 0.3)
			(layers "F.Cu" "F.Paste" "F.Mask")
			(net 438 "/SoM/SoM_VIN")
			(pinfunction "VDD_IN")
			(pintype "passive")
		)
		(pad "252" smd rect
			(at -31.38 -3.826 90)
			(size 1.75 0.3)
			(layers "F.Cu" "F.Paste" "F.Mask")
			(net 438 "/SoM/SoM_VIN")
			(pinfunction "VDD_IN")
			(pintype "passive")
		)
	)
)
